(kicad_pcb
	(version 20241229)
	(generator "pcbnew")
	(generator_version "9.0")
	(general
		(thickness 0.761)
		(legacy_teardrops no)
	)
	(paper "A4")
	(title_block
		(title " M.2 to OCuLink adapter")
		(date "2025-07-16")
		(rev "1.0.2")
		(company "Antmicro Ltd")
		(comment 1 "www.antmicro.com")
		(comment 9 "footprint 4 of 22 (J1), pads 46-67 of 67")
	)
	(layers
		(0 "F.Cu" signal)
		(4 "In1.Cu" signal)
		(6 "In2.Cu" signal)
		(2 "B.Cu" signal)
		(9 "F.Adhes" user "F.Adhesive")
		(11 "B.Adhes" user "B.Adhesive")
		(13 "F.Paste" user)
		(15 "B.Paste" user)
		(5 "F.SilkS" user "F.Silkscreen")
		(7 "B.SilkS" user "B.Silkscreen")
		(1 "F.Mask" user)
		(3 "B.Mask" user)
		(17 "Dwgs.User" user "User.Drawings")
		(19 "Cmts.User" user "User.Comments")
		(21 "Eco1.User" user "User.Eco1")
		(23 "Eco2.User" user "User.Eco2")
		(25 "Edge.Cuts" user)
		(27 "Margin" user)
		(31 "F.CrtYd" user "F.Courtyard")
		(29 "B.CrtYd" user "B.Courtyard")
		(35 "F.Fab" user)
		(33 "B.Fab" user)
	)
	(footprint "antmicro-footprints:PCB-Edge_M.2_Key-M"
		(locked yes)
		(layer "F.Cu")
		(at 146.3 130.6)
		(property "Reference" "J1"
			(at 10.05 -5.7 0)
			(layer "F.SilkS")
			(hide yes)
			(effects
				(font
					(size 0.7 0.7)
					(thickness 0.15)
				)
				(justify left bottom)
			)
		)
		(property "Value" "PCB-Edge_M.2_Key-M"
			(at -0.075 2.25 0)
			(layer "F.Fab")
			(effects
				(font
					(size 0.7 0.7)
					(thickness 0.15)
				)
				(justify left bottom)
			)
		)
		(property "Datasheet" "https://www.amphenol-icc.com/media/wysiwyg/files/drawing/10130618.pdf"
			(at 0 0 0)
			(layer "F.Fab")
			(hide yes)
			(effects
				(font
					(size 1.27 1.27)
					(thickness 0.15)
				)
			)
		)
		(property "Description" "PCB Edge for M.2 key M"
			(at 0 0 0)
			(layer "F.Fab")
			(hide yes)
			(effects
				(font
					(size 1.27 1.27)
					(thickness 0.15)
				)
			)
		)
		(property "Author" "Antmicro"
			(at 0 0 0)
			(unlocked yes)
			(layer "F.Fab")
			(hide yes)
			(effects
				(font
					(size 1 1)
					(thickness 0.15)
				)
			)
		)
		(property "License" "Apache-2.0"
			(at 0 0 0)
			(unlocked yes)
			(layer "F.Fab")
			(hide yes)
			(effects
				(font
					(size 1 1)
					(thickness 0.15)
				)
			)
		)
		(sheetname "/")
		(sheetfile "antmicro-m2-oculink-adapter-hw.kicad_sch")
		(clearance 0)
		(attr exclude_from_pos_files exclude_from_bom)
		(pad "46" smd rect
			(at -2.154757 -1.7)
			(size 0.35 3)
			(layers "B.Cu" "B.Mask")
			(net 47 "unconnected-(J1-NC-Pad46)")
			(pinfunction "NC")
			(pintype "no_connect")
			(teardrops
				(best_length_ratio 0.5)
				(max_length 1)
				(best_width_ratio 1)
				(max_width 2)
				(curved_edges yes)
				(filter_ratio 0.9)
				(enabled no)
				(allow_two_segments yes)
				(prefer_zone_connections no)
			)
		)
		(pad "47" smd rect
			(at -2.4 -1.45)
			(size 0.35 2.5)
			(layers "F.Cu" "F.Mask")
			(net 15 "/PCIe_{x4}.TX0-")
			(pinfunction "PETn0")
			(pintype "passive")
			(teardrops
				(best_length_ratio 0.5)
				(max_length 1)
				(best_width_ratio 1)
				(max_width 2)
				(curved_edges yes)
				(filter_ratio 0.9)
				(enabled no)
				(allow_two_segments yes)
				(prefer_zone_connections no)
			)
		)
		(pad "48" smd rect
			(at -2.654757 -1.7)
			(size 0.35 3)
			(layers "B.Cu" "B.Mask")
			(net 22 "unconnected-(J1-NC-Pad48)")
			(pinfunction "NC")
			(pintype "no_connect")
			(teardrops
				(best_length_ratio 0.5)
				(max_length 1)
				(best_width_ratio 1)
				(max_width 2)
				(curved_edges yes)
				(filter_ratio 0.9)
				(enabled no)
				(allow_two_segments yes)
				(prefer_zone_connections no)
			)
		)
		(pad "49" smd rect
			(at -2.9 -1.45)
			(size 0.35 2.5)
			(layers "F.Cu" "F.Mask")
			(net 25 "/PCIe_{x4}.TX0+")
			(pinfunction "PETp0")
			(pintype "passive")
			(teardrops
				(best_length_ratio 0.5)
				(max_length 1)
				(best_width_ratio 1)
				(max_width 2)
				(curved_edges yes)
				(filter_ratio 0.9)
				(enabled no)
				(allow_two_segments yes)
				(prefer_zone_connections no)
			)
		)
		(pad "50" smd rect
			(at -3.154757 -1.7)
			(size 0.35 3)
			(layers "B.Cu" "B.Mask")
			(net 55 "/~{PERST}")
			(pinfunction "PERST#")
			(pintype "passive")
			(teardrops
				(best_length_ratio 0.5)
				(max_length 1)
				(best_width_ratio 1)
				(max_width 2)
				(curved_edges yes)
				(filter_ratio 0.9)
				(enabled no)
				(allow_two_segments yes)
				(prefer_zone_connections no)
			)
		)
		(pad "51" smd rect
			(at -3.4 -1.45)
			(size 0.35 2.5)
			(layers "F.Cu" "F.Mask")
			(net 1 "GND")
			(pinfunction "GND")
			(pintype "passive")
			(teardrops
				(best_length_ratio 0.5)
				(max_length 1)
				(best_width_ratio 1)
				(max_width 2)
				(curved_edges yes)
				(filter_ratio 0.9)
				(enabled no)
				(allow_two_segments yes)
				(prefer_zone_connections no)
			)
		)
		(pad "52" smd rect
			(at -3.654757 -1.7)
			(size 0.35 3)
			(layers "B.Cu" "B.Mask")
			(net 41 "Net-(J1-CLKREQ#)")
			(pinfunction "CLKREQ#")
			(pintype "passive")
			(teardrops
				(best_length_ratio 0.5)
				(max_length 1)
				(best_width_ratio 1)
				(max_width 2)
				(curved_edges yes)
				(filter_ratio 0.9)
				(enabled no)
				(allow_two_segments yes)
				(prefer_zone_connections no)
			)
		)
		(pad "53" smd rect
			(at -3.9 -1.45)
			(size 0.35 2.5)
			(layers "F.Cu" "F.Mask")
			(net 36 "/PCIe_{REF0}.CK+")
			(pinfunction "REFCLKn")
			(pintype "passive")
			(teardrops
				(best_length_ratio 0.5)
				(max_length 1)
				(best_width_ratio 1)
				(max_width 2)
				(curved_edges yes)
				(filter_ratio 0.9)
				(enabled no)
				(allow_two_segments yes)
				(prefer_zone_connections no)
			)
		)
		(pad "54" smd rect
			(at -4.154757 -1.7)
			(size 0.35 3)
			(layers "B.Cu" "B.Mask")
			(net 37 "/~{WAKE}")
			(pinfunction "PEWAKE#")
			(pintype "passive")
			(teardrops
				(best_length_ratio 0.5)
				(max_length 1)
				(best_width_ratio 1)
				(max_width 2)
				(curved_edges yes)
				(filter_ratio 0.9)
				(enabled no)
				(allow_two_segments yes)
				(prefer_zone_connections no)
			)
		)
		(pad "55" smd rect
			(at -4.4 -1.45)
			(size 0.35 2.5)
			(layers "F.Cu" "F.Mask")
			(net 38 "/PCIe_{REF0}.CK-")
			(pinfunction "REFCLKp")
			(pintype "passive")
			(teardrops
				(best_length_ratio 0.5)
				(max_length 1)
				(best_width_ratio 1)
				(max_width 2)
				(curved_edges yes)
				(filter_ratio 0.9)
				(enabled no)
				(allow_two_segments yes)
				(prefer_zone_connections no)
			)
		)
		(pad "56" smd rect
			(at -4.654757 -1.7)
			(size 0.35 3)
			(layers "B.Cu" "B.Mask")
			(net 39 "unconnected-(J1-NC-Pad56)")
			(pinfunction "NC")
			(pintype "no_connect")
			(teardrops
				(best_length_ratio 0.5)
				(max_length 1)
				(best_width_ratio 1)
				(max_width 2)
				(curved_edges yes)
				(filter_ratio 0.9)
				(enabled no)
				(allow_two_segments yes)
				(prefer_zone_connections no)
			)
		)
		(pad "57" smd rect
			(at -4.9 -1.45)
			(size 0.35 2.5)
			(layers "F.Cu" "F.Mask")
			(net 1 "GND")
			(pinfunction "GND")
			(pintype "passive")
			(teardrops
				(best_length_ratio 0.5)
				(max_length 1)
				(best_width_ratio 1)
				(max_width 2)
				(curved_edges yes)
				(filter_ratio 0.9)
				(enabled no)
				(allow_two_segments yes)
				(prefer_zone_connections no)
			)
		)
		(pad "58" smd rect
			(at -5.154757 -1.7)
			(size 0.35 3)
			(layers "B.Cu" "B.Mask")
			(net 20 "unconnected-(J1-NC-Pad58)")
			(pinfunction "NC")
			(pintype "no_connect")
			(teardrops
				(best_length_ratio 0.5)
				(max_length 1)
				(best_width_ratio 1)
				(max_width 2)
				(curved_edges yes)
				(filter_ratio 0.9)
				(enabled no)
				(allow_two_segments yes)
				(prefer_zone_connections no)
			)
		)
		(pad "67" smd rect
			(at -7.4 -1.45)
			(size 0.35 2.5)
			(layers "F.Cu" "F.Mask")
			(net 30 "unconnected-(J1-NC-Pad67)")
			(pinfunction "NC")
			(pintype "no_connect")
			(teardrops
				(best_length_ratio 0.5)
				(max_length 1)
				(best_width_ratio 1)
				(max_width 2)
				(curved_edges yes)
				(filter_ratio 0.9)
				(enabled no)
				(allow_two_segments yes)
				(prefer_zone_connections no)
			)
		)
		(pad "68" smd rect
			(at -7.654757 -1.7)
			(size 0.35 3)
			(layers "B.Cu" "B.Mask")
			(net 11 "unconnected-(J1-SUSCLK-Pad68)")
			(pinfunction "SUSCLK")
			(pintype "passive+no_connect")
			(teardrops
				(best_length_ratio 0.5)
				(max_length 1)
				(best_width_ratio 1)
				(max_width 2)
				(curved_edges yes)
				(filter_ratio 0.9)
				(enabled no)
				(allow_two_segments yes)
				(prefer_zone_connections no)
			)
		)
		(pad "69" smd rect
			(at -7.9 -1.45)
			(size 0.35 2.5)
			(layers "F.Cu" "F.Mask")
			(net 33 "unconnected-(J1-PEDET-Pad69)")
			(pinfunction "PEDET")
			(pintype "passive+no_connect")
			(teardrops
				(best_length_ratio 0.5)
				(max_length 1)
				(best_width_ratio 1)
				(max_width 2)
				(curved_edges yes)
				(filter_ratio 0.9)
				(enabled no)
				(allow_two_segments yes)
				(prefer_zone_connections no)
			)
		)
		(pad "70" smd rect
			(at -8.154757 -1.7)
			(size 0.35 3)
			(layers "B.Cu" "B.Mask")
			(net 56 "Net-(C1-Pad2)")
			(pinfunction "3.3V")
			(pintype "passive")
			(teardrops
				(best_length_ratio 0.5)
				(max_length 1)
				(best_width_ratio 1)
				(max_width 2)
				(curved_edges yes)
				(filter_ratio 0.9)
				(enabled no)
				(allow_two_segments yes)
				(prefer_zone_connections no)
			)
		)
		(pad "71" smd rect
			(at -8.4 -1.45)
			(size 0.35 2.5)
			(layers "F.Cu" "F.Mask")
			(net 1 "GND")
			(pinfunction "GND")
			(pintype "passive")
			(teardrops
				(best_length_ratio 0.5)
				(max_length 1)
				(best_width_ratio 1)
				(max_width 2)
				(curved_edges yes)
				(filter_ratio 0.9)
				(enabled no)
				(allow_two_segments yes)
				(prefer_zone_connections no)
			)
		)
		(pad "72" smd rect
			(at -8.654757 -1.7)
			(size 0.35 3)
			(layers "B.Cu" "B.Mask")
			(net 56 "Net-(C1-Pad2)")
			(pinfunction "3.3V")
			(pintype "passive")
			(teardrops
				(best_length_ratio 0.5)
				(max_length 1)
				(best_width_ratio 1)
				(max_width 2)
				(curved_edges yes)
				(filter_ratio 0.9)
				(enabled no)
				(allow_two_segments yes)
				(prefer_zone_connections no)
			)
		)
		(pad "73" smd rect
			(at -8.9 -1.45)
			(size 0.35 2.5)
			(layers "F.Cu" "F.Mask")
			(net 1 "GND")
			(pinfunction "GND")
			(pintype "passive")
			(teardrops
				(best_length_ratio 0.5)
				(max_length 1)
				(best_width_ratio 1)
				(max_width 2)
				(curved_edges yes)
				(filter_ratio 0.9)
				(enabled no)
				(allow_two_segments yes)
				(prefer_zone_connections no)
			)
		)
		(pad "74" smd rect
			(at -9.154757 -1.7)
			(size 0.35 3)
			(layers "B.Cu" "B.Mask")
			(net 56 "Net-(C1-Pad2)")
			(pinfunction "3.3V")
			(pintype "passive")
			(teardrops
				(best_length_ratio 0.5)
				(max_length 1)
				(best_width_ratio 1)
				(max_width 2)
				(curved_edges yes)
				(filter_ratio 0.9)
				(enabled no)
				(allow_two_segments yes)
				(prefer_zone_connections no)
			)
		)
		(pad "75" smd rect
			(at -9.404757 -1.45)
			(size 0.35 2.5)
			(layers "F.Cu" "F.Mask")
			(net 1 "GND")
			(pinfunction "GND")
			(pintype "passive")
			(teardrops
				(best_length_ratio 0.5)
				(max_length 1)
				(best_width_ratio 1)
				(max_width 2)
				(curved_edges yes)
				(filter_ratio 0.9)
				(enabled no)
				(allow_two_segments yes)
				(prefer_zone_connections no)
			)
		)
	)
)
